(kicad_pcb
	(version 20260206)
	(generator "pcbnew")
	(generator_version "10.0")
	(general
		(thickness 1.6)
		(legacy_teardrops no)
	)
	(paper "A4")
	(title_block
		(title "peb — Lightning_PEB_BRD.brd")
		(comment 1 "Lightning (Wiwynn / Facebook NVMe JBOF) / footprints 196-202 of 2563")
	)
	(layers
		(0 "F.Cu" signal "TOP")
		(4 "In1.Cu" signal "L2GND")
		(6 "In2.Cu" signal "L3")
		(8 "In3.Cu" signal "L4VCC")
		(10 "In4.Cu" signal "L5VCC")
		(12 "In5.Cu" signal "L6")
		(14 "In6.Cu" signal "L7GND")
		(2 "B.Cu" signal "BOTTOM")
		(9 "F.Adhes" user "F.Adhesive")
		(11 "B.Adhes" user "B.Adhesive")
		(13 "F.Paste" user "Package Geometry/Pastemask Top")
		(15 "B.Paste" user "Package Geometry/Pastemask Bottom")
		(5 "F.SilkS" user "Ref Des/Silkscreen Top")
		(7 "B.SilkS" user "Ref Des/Silkscreen Bottom")
		(1 "F.Mask" user "Board Geometry/Soldermask Top")
		(3 "B.Mask" user "Board Geometry/Soldermask Bottom")
		(17 "Dwgs.User" user "User.Drawings")
		(19 "Cmts.User" user "User.Comments")
		(21 "Eco1.User" user "User.Eco1")
		(23 "Eco2.User" user "User.Eco2")
		(25 "Edge.Cuts" user "Board Geometry/Outline")
		(27 "Margin" user)
		(31 "F.CrtYd" user "Package Geometry/Place Bound Top")
		(29 "B.CrtYd" user "Package Geometry/Place Bound Bottom")
		(35 "F.Fab" user "Ref Des/Assembly Top")
		(33 "B.Fab" user "Ref Des/Assembly Bottom")
	)
	(footprint ""
		(layer "F.Cu")
		(at 268.31544 -17.61617 90)
		(property "Reference" "SR722"
			(at 0 0 90)
			(layer "F.SilkS")
			(hide yes)
			(effects
				(font
					(size 1.27 1.27)
				)
			)
		)
		(property "Value" "150R2F-1-GP"
			(at 0.064008 -3.993896 90)
			(unlocked yes)
			(layer "F.Fab")
			(hide yes)
			(effects
				(font
					(size 1.016 1.016)
					(thickness 0.1524)
				)
			)
		)
		(property "Device Type" "R402H16"
			(at 0.064008 -5.517896 90)
			(unlocked yes)
			(layer "F.Fab")
			(hide yes)
			(effects
				(font
					(size 1.016 1.016)
					(thickness 0.1524)
				)
			)
		)
		(duplicate_pad_numbers_are_jumpers no)
		(fp_line
			(start 0.508 -0.9398)
			(end -0.508 -0.9398)
			(stroke
				(width 0.1524)
				(type default)
			)
			(layer "F.SilkS")
		)
		(fp_line
			(start -0.508 -0.9398)
			(end -0.508 0.9398)
			(stroke
				(width 0.1524)
				(type default)
			)
			(layer "F.SilkS")
		)
		(fp_rect
			(start -0.508 0.9398)
			(end 0.508 -0.9398)
			(stroke
				(width 0)
				(type default)
			)
			(fill no)
			(layer "F.CrtYd")
		)
		(fp_rect
			(start -0.508 0.9398)
			(end 0.508 -0.9398)
			(stroke
				(width 0)
				(type default)
			)
			(fill no)
			(layer "F.Fab")
		)
		(pad "1" smd custom
			(at 0 -0.4445 90)
			(size 0.1397 0.1397)
			(layers "F.Cu" "F.Mask" "F.Paste")
			(net "P3V3_STBY")
			(options
				(clearance outline)
				(anchor circle)
			)
			(primitives
				(gr_poly
					(pts
						(arc
							(start -0.1778 -0.2794)
							(mid -0.249642 -0.249642)
							(end -0.2794 -0.1778)
						)
						(arc
							(start -0.2794 0.1778)
							(mid -0.249642 0.249642)
							(end -0.1778 0.2794)
						)
						(arc
							(start 0.1778 0.2794)
							(mid 0.249642 0.249642)
							(end 0.2794 0.1778)
						)
						(arc
							(start 0.2794 -0.1778)
							(mid 0.249642 -0.249642)
							(end 0.1778 -0.2794)
						)
					)
					(width 0)
					(fill yes)
				)
			)
		)
		(pad "2" smd custom
			(at 0 0.4445 90)
			(size 0.1397 0.1397)
			(layers "F.Cu" "F.Mask" "F.Paste")
			(net "LED_R_13")
			(options
				(clearance outline)
				(anchor circle)
			)
			(primitives
				(gr_poly
					(pts
						(arc
							(start -0.1778 -0.2794)
							(mid -0.249642 -0.249642)
							(end -0.2794 -0.1778)
						)
						(arc
							(start -0.2794 0.1778)
							(mid -0.249642 0.249642)
							(end -0.1778 0.2794)
						)
						(arc
							(start 0.1778 0.2794)
							(mid 0.249642 0.249642)
							(end 0.2794 0.1778)
						)
						(arc
							(start 0.2794 -0.1778)
							(mid 0.249642 -0.249642)
							(end 0.1778 -0.2794)
						)
					)
					(width 0)
					(fill yes)
				)
			)
		)
	)
	(footprint ""
		(layer "F.Cu")
		(at 33.1978 -189.2808 -90)
		(property "Reference" "R486"
			(at 0 0 270)
			(layer "F.SilkS")
			(hide yes)
			(effects
				(font
					(size 1.27 1.27)
				)
			)
		)
		(property "Value" "10KR2F-2-GP"
			(at 0.064008 -3.993896 270)
			(unlocked yes)
			(layer "F.Fab")
			(hide yes)
			(effects
				(font
					(size 1.016 1.016)
					(thickness 0.1524)
				)
			)
		)
		(property "Device Type" "R402H16"
			(at 0.064008 -5.517896 270)
			(unlocked yes)
			(layer "F.Fab")
			(hide yes)
			(effects
				(font
					(size 1.016 1.016)
					(thickness 0.1524)
				)
			)
		)
		(duplicate_pad_numbers_are_jumpers no)
		(fp_line
			(start -0.508 -0.9398)
			(end -0.508 0.9398)
			(stroke
				(width 0.1524)
				(type default)
			)
			(layer "F.SilkS")
		)
		(fp_line
			(start 0.508 -0.9398)
			(end -0.508 -0.9398)
			(stroke
				(width 0.1524)
				(type default)
			)
			(layer "F.SilkS")
		)
		(fp_rect
			(start -0.508 0.9398)
			(end 0.508 -0.9398)
			(stroke
				(width 0)
				(type default)
			)
			(fill no)
			(layer "F.CrtYd")
		)
		(fp_rect
			(start -0.508 0.9398)
			(end 0.508 -0.9398)
			(stroke
				(width 0)
				(type default)
			)
			(fill no)
			(layer "F.Fab")
		)
		(pad "1" smd custom
			(at 0 -0.4445 270)
			(size 0.1397 0.1397)
			(layers "F.Cu" "F.Mask" "F.Paste")
			(net "P3V3_STBY")
			(options
				(clearance outline)
				(anchor circle)
			)
			(primitives
				(gr_poly
					(pts
						(arc
							(start -0.1778 -0.2794)
							(mid -0.249642 -0.249642)
							(end -0.2794 -0.1778)
						)
						(arc
							(start -0.2794 0.1778)
							(mid -0.249642 0.249642)
							(end -0.1778 0.2794)
						)
						(arc
							(start 0.1778 0.2794)
							(mid 0.249642 0.249642)
							(end 0.2794 0.1778)
						)
						(arc
							(start 0.2794 -0.1778)
							(mid 0.249642 -0.249642)
							(end 0.1778 -0.2794)
						)
					)
					(width 0)
					(fill yes)
				)
			)
		)
		(pad "2" smd custom
			(at 0 0.4445 270)
			(size 0.1397 0.1397)
			(layers "F.Cu" "F.Mask" "F.Paste")
			(net "I2C5_BUFF_EN")
			(options
				(clearance outline)
				(anchor circle)
			)
			(primitives
				(gr_poly
					(pts
						(arc
							(start -0.1778 -0.2794)
							(mid -0.249642 -0.249642)
							(end -0.2794 -0.1778)
						)
						(arc
							(start -0.2794 0.1778)
							(mid -0.249642 0.249642)
							(end -0.1778 0.2794)
						)
						(arc
							(start 0.1778 0.2794)
							(mid 0.249642 0.249642)
							(end 0.2794 0.1778)
						)
						(arc
							(start 0.2794 -0.1778)
							(mid 0.249642 -0.249642)
							(end 0.1778 -0.2794)
						)
					)
					(width 0)
					(fill yes)
				)
			)
		)
	)
	(footprint ""
		(layer "F.Cu")
		(at 223.2152 -13.8684)
		(property "Reference" "C271"
			(at 0 0 0)
			(layer "F.SilkS")
			(hide yes)
			(effects
				(font
					(size 1.27 1.27)
				)
			)
		)
		(property "Value" "SC1U10V2KX-4-GP"
			(at 1.1811 -2.7051 0)
			(unlocked yes)
			(layer "F.Fab")
			(hide yes)
			(effects
				(font
					(size 1.016 1.016)
					(thickness 0.1524)
				)
			)
		)
		(property "Device Type" "C402H22"
			(at 1.1811 -4.2291 0)
			(unlocked yes)
			(layer "F.Fab")
			(hide yes)
			(effects
				(font
					(size 1.016 1.016)
					(thickness 0.1524)
				)
			)
		)
		(duplicate_pad_numbers_are_jumpers no)
		(fp_rect
			(start -0.4318 0.9525)
			(end 0.4318 -0.9525)
			(stroke
				(width 0)
				(type default)
			)
			(fill no)
			(layer "F.CrtYd")
		)
		(fp_rect
			(start -0.4318 0.9525)
			(end 0.4318 -0.9525)
			(stroke
				(width 0)
				(type default)
			)
			(fill no)
			(layer "F.Fab")
		)
		(pad "1" smd custom
			(at 0 -0.4445)
			(size 0.1524 0.1524)
			(layers "F.Cu" "F.Mask" "F.Paste")
			(net "U82_MR#")
			(options
				(clearance outline)
				(anchor circle)
			)
			(primitives
				(gr_poly
					(pts
						(arc
							(start 0.3048 -0.2032)
							(mid 0.275042 -0.275042)
							(end 0.2032 -0.3048)
						)
						(arc
							(start -0.2032 -0.3048)
							(mid -0.275042 -0.275042)
							(end -0.3048 -0.2032)
						)
						(arc
							(start -0.3048 0.2032)
							(mid -0.275042 0.275042)
							(end -0.2032 0.3048)
						)
						(arc
							(start 0.2032 0.3048)
							(mid 0.275042 0.275042)
							(end 0.3048 0.2032)
						)
					)
					(width 0)
					(fill yes)
				)
			)
		)
		(pad "2" smd custom
			(at 0 0.4445)
			(size 0.1524 0.1524)
			(layers "F.Cu" "F.Mask" "F.Paste")
			(net "GND")
			(options
				(clearance outline)
				(anchor circle)
			)
			(primitives
				(gr_poly
					(pts
						(arc
							(start 0.3048 -0.2032)
							(mid 0.275042 -0.275042)
							(end 0.2032 -0.3048)
						)
						(arc
							(start -0.2032 -0.3048)
							(mid -0.275042 -0.275042)
							(end -0.3048 -0.2032)
						)
						(arc
							(start -0.3048 0.2032)
							(mid -0.275042 0.275042)
							(end -0.2032 0.3048)
						)
						(arc
							(start 0.2032 0.3048)
							(mid 0.275042 0.275042)
							(end 0.3048 0.2032)
						)
					)
					(width 0)
					(fill yes)
				)
			)
		)
	)
	(footprint ""
		(layer "F.Cu")
		(at 174.721774 -51.102768 180)
		(property "Reference" "Q32"
			(at 0 0 180)
			(layer "F.SilkS")
			(hide yes)
			(effects
				(font
					(size 1.27 1.27)
				)
			)
		)
		(property "Value" "2N7002K-1-GP"
			(at 0.127 -8.9662 180)
			(unlocked yes)
			(layer "F.Fab")
			(hide yes)
			(effects
				(font
					(size 1.016 1.016)
					(thickness 0.1524)
				)
			)
		)
		(property "Device Type" "SOT23DGS2D4H44"
			(at 0.127 -10.4902 180)
			(unlocked yes)
			(layer "F.Fab")
			(hide yes)
			(effects
				(font
					(size 1.016 1.016)
					(thickness 0.1524)
				)
			)
		)
		(duplicate_pad_numbers_are_jumpers no)
		(fp_line
			(start 1.651 1.778)
			(end 1.651 -1.778)
			(stroke
				(width 0.1524)
				(type default)
			)
			(layer "F.SilkS")
		)
		(fp_line
			(start 1.651 -1.778)
			(end -1.651 -1.778)
			(stroke
				(width 0.1524)
				(type default)
			)
			(layer "F.SilkS")
		)
		(fp_line
			(start -1.651 1.778)
			(end 1.651 1.778)
			(stroke
				(width 0.1524)
				(type default)
			)
			(layer "F.SilkS")
		)
		(fp_line
			(start -1.651 -1.778)
			(end -1.651 1.778)
			(stroke
				(width 0.1524)
				(type default)
			)
			(layer "F.SilkS")
		)
		(fp_poly
			(pts
				(xy -1.778 1.8796) (xy -1.778 -1.8796) (xy 1.778 -1.8796) (xy 1.778 1.8796)
			)
			(stroke
				(width 0)
				(type default)
			)
			(fill no)
			(layer "F.CrtYd")
		)
		(fp_poly
			(pts
				(xy -1.778 1.8796) (xy -1.778 -1.8796) (xy 1.778 -1.8796) (xy 1.778 1.8796)
			)
			(stroke
				(width 0)
				(type default)
			)
			(fill no)
			(layer "F.Fab")
		)
		(pad "D" smd custom
			(at 0 -0.9525 180)
			(size 0.1905 0.1905)
			(layers "F.Cu" "F.Mask" "F.Paste")
			(net "LED_Q_11")
			(options
				(clearance outline)
				(anchor circle)
			)
			(primitives
				(gr_poly
					(pts
						(arc
							(start -0.1778 0.5715)
							(mid -0.321484 0.511984)
							(end -0.381 0.3683)
						)
						(arc
							(start -0.381 -0.3683)
							(mid -0.321484 -0.511984)
							(end -0.1778 -0.5715)
						)
						(arc
							(start 0.1778 -0.5715)
							(mid 0.321484 -0.511984)
							(end 0.381 -0.3683)
						)
						(arc
							(start 0.381 0.3683)
							(mid 0.321484 0.511984)
							(end 0.1778 0.5715)
						)
					)
					(width 0)
					(fill yes)
				)
			)
		)
		(pad "G" smd custom
			(at -0.98425 0.9525 180)
			(size 0.1905 0.1905)
			(layers "F.Cu" "F.Mask" "F.Paste")
			(net "VS3_LED_R")
			(options
				(clearance outline)
				(anchor circle)
			)
			(primitives
				(gr_poly
					(pts
						(arc
							(start -0.1778 0.5715)
							(mid -0.321484 0.511984)
							(end -0.381 0.3683)
						)
						(arc
							(start -0.381 -0.3683)
							(mid -0.321484 -0.511984)
							(end -0.1778 -0.5715)
						)
						(arc
							(start 0.1778 -0.5715)
							(mid 0.321484 -0.511984)
							(end 0.381 -0.3683)
						)
						(arc
							(start 0.381 0.3683)
							(mid 0.321484 0.511984)
							(end 0.1778 0.5715)
						)
					)
					(width 0)
					(fill yes)
				)
			)
		)
		(pad "S" smd custom
			(at 0.98425 0.9525 180)
			(size 0.1905 0.1905)
			(layers "F.Cu" "F.Mask" "F.Paste")
			(net "GND")
			(options
				(clearance outline)
				(anchor circle)
			)
			(primitives
				(gr_poly
					(pts
						(arc
							(start -0.1778 0.5715)
							(mid -0.321484 0.511984)
							(end -0.381 0.3683)
						)
						(arc
							(start -0.381 -0.3683)
							(mid -0.321484 -0.511984)
							(end -0.1778 -0.5715)
						)
						(arc
							(start 0.1778 -0.5715)
							(mid 0.321484 -0.511984)
							(end 0.381 -0.3683)
						)
						(arc
							(start 0.381 0.3683)
							(mid 0.321484 0.511984)
							(end 0.1778 0.5715)
						)
					)
					(width 0)
					(fill yes)
				)
			)
		)
	)
	(footprint ""
		(layer "F.Cu")
		(at 124.944124 -196.443092 180)
		(property "Reference" "R547"
			(at 0 0 180)
			(layer "F.SilkS")
			(hide yes)
			(effects
				(font
					(size 1.27 1.27)
				)
			)
		)
		(property "Value" "10KR2F-2-GP"
			(at 0.064008 -3.993896 180)
			(unlocked yes)
			(layer "F.Fab")
			(hide yes)
			(effects
				(font
					(size 1.016 1.016)
					(thickness 0.1524)
				)
			)
		)
		(property "Device Type" "R402H16"
			(at 0.064008 -5.517896 180)
			(unlocked yes)
			(layer "F.Fab")
			(hide yes)
			(effects
				(font
					(size 1.016 1.016)
					(thickness 0.1524)
				)
			)
		)
		(duplicate_pad_numbers_are_jumpers no)
		(fp_line
			(start 0.508 -0.9398)
			(end -0.508 -0.9398)
			(stroke
				(width 0.1524)
				(type default)
			)
			(layer "F.SilkS")
		)
		(fp_line
			(start -0.508 -0.9398)
			(end -0.508 0.9398)
			(stroke
				(width 0.1524)
				(type default)
			)
			(layer "F.SilkS")
		)
		(fp_rect
			(start -0.508 0.9398)
			(end 0.508 -0.9398)
			(stroke
				(width 0)
				(type default)
			)
			(fill no)
			(layer "F.CrtYd")
		)
		(fp_rect
			(start -0.508 0.9398)
			(end 0.508 -0.9398)
			(stroke
				(width 0)
				(type default)
			)
			(fill no)
			(layer "F.Fab")
		)
		(pad "1" smd custom
			(at 0 -0.4445 180)
			(size 0.1397 0.1397)
			(layers "F.Cu" "F.Mask" "F.Paste")
			(net "GND")
			(options
				(clearance outline)
				(anchor circle)
			)
			(primitives
				(gr_poly
					(pts
						(arc
							(start -0.1778 -0.2794)
							(mid -0.249642 -0.249642)
							(end -0.2794 -0.1778)
						)
						(arc
							(start -0.2794 0.1778)
							(mid -0.249642 0.249642)
							(end -0.1778 0.2794)
						)
						(arc
							(start 0.1778 0.2794)
							(mid 0.249642 0.249642)
							(end 0.2794 0.1778)
						)
						(arc
							(start 0.2794 -0.1778)
							(mid 0.249642 -0.249642)
							(end 0.1778 -0.2794)
						)
					)
					(width 0)
					(fill yes)
				)
			)
		)
		(pad "2" smd custom
			(at 0 0.4445 180)
			(size 0.1397 0.1397)
			(layers "F.Cu" "F.Mask" "F.Paste")
			(net "IOEXP2_AD2")
			(options
				(clearance outline)
				(anchor circle)
			)
			(primitives
				(gr_poly
					(pts
						(arc
							(start -0.1778 -0.2794)
							(mid -0.249642 -0.249642)
							(end -0.2794 -0.1778)
						)
						(arc
							(start -0.2794 0.1778)
							(mid -0.249642 0.249642)
							(end -0.1778 0.2794)
						)
						(arc
							(start 0.1778 0.2794)
							(mid 0.249642 0.249642)
							(end 0.2794 0.1778)
						)
						(arc
							(start 0.2794 -0.1778)
							(mid 0.249642 -0.249642)
							(end 0.1778 -0.2794)
						)
					)
					(width 0)
					(fill yes)
				)
			)
		)
	)
	(footprint ""
		(layer "F.Cu")
		(at 37.035486 -146.46402)
		(property "Reference" "C175"
			(at 0 0 0)
			(layer "F.SilkS")
			(hide yes)
			(effects
				(font
					(size 1.27 1.27)
				)
			)
		)
		(property "Value" "SCD1U16V2KX-3GP"
			(at 1.1811 -2.7051 0)
			(unlocked yes)
			(layer "F.Fab")
			(hide yes)
			(effects
				(font
					(size 1.016 1.016)
					(thickness 0.1524)
				)
			)
		)
		(property "Device Type" "C402H22"
			(at 1.1811 -4.2291 0)
			(unlocked yes)
			(layer "F.Fab")
			(hide yes)
			(effects
				(font
					(size 1.016 1.016)
					(thickness 0.1524)
				)
			)
		)
		(duplicate_pad_numbers_are_jumpers no)
		(fp_rect
			(start -0.4318 0.9525)
			(end 0.4318 -0.9525)
			(stroke
				(width 0)
				(type default)
			)
			(fill no)
			(layer "F.CrtYd")
		)
		(fp_rect
			(start -0.4318 0.9525)
			(end 0.4318 -0.9525)
			(stroke
				(width 0)
				(type default)
			)
			(fill no)
			(layer "F.Fab")
		)
		(pad "1" smd custom
			(at 0 -0.4445)
			(size 0.1524 0.1524)
			(layers "F.Cu" "F.Mask" "F.Paste")
			(net "P1V53_STBY")
			(options
				(clearance outline)
				(anchor circle)
			)
			(primitives
				(gr_poly
					(pts
						(arc
							(start 0.3048 -0.2032)
							(mid 0.275042 -0.275042)
							(end 0.2032 -0.3048)
						)
						(arc
							(start -0.2032 -0.3048)
							(mid -0.275042 -0.275042)
							(end -0.3048 -0.2032)
						)
						(arc
							(start -0.3048 0.2032)
							(mid -0.275042 0.275042)
							(end -0.2032 0.3048)
						)
						(arc
							(start 0.2032 0.3048)
							(mid 0.275042 0.275042)
							(end 0.3048 0.2032)
						)
					)
					(width 0)
					(fill yes)
				)
			)
		)
		(pad "2" smd custom
			(at 0 0.4445)
			(size 0.1524 0.1524)
			(layers "F.Cu" "F.Mask" "F.Paste")
			(net "GND")
			(options
				(clearance outline)
				(anchor circle)
			)
			(primitives
				(gr_poly
					(pts
						(arc
							(start 0.3048 -0.2032)
							(mid 0.275042 -0.275042)
							(end 0.2032 -0.3048)
						)
						(arc
							(start -0.2032 -0.3048)
							(mid -0.275042 -0.275042)
							(end -0.3048 -0.2032)
						)
						(arc
							(start -0.3048 0.2032)
							(mid -0.275042 0.275042)
							(end -0.2032 0.3048)
						)
						(arc
							(start 0.2032 0.3048)
							(mid 0.275042 0.275042)
							(end 0.3048 0.2032)
						)
					)
					(width 0)
					(fill yes)
				)
			)
		)
	)
	(footprint ""
		(layer "F.Cu")
		(at 35.306 -56.896 180)
		(property "Reference" "F1"
			(at 0 0 180)
			(layer "F.SilkS")
			(hide yes)
			(effects
				(font
					(size 1.27 1.27)
				)
			)
		)
		(property "Value" "POLYSW-1D5A8V-4-GP"
			(at -2.401824 -0.181102 180)
			(unlocked yes)
			(layer "F.Fab")
			(hide yes)
			(effects
				(font
					(size 1.016 1.016)
					(thickness 0.1524)
				)
			)
		)
		(property "Device Type" "POLYSW-3217-UH40"
			(at -2.401824 -1.705102 180)
			(unlocked yes)
			(layer "F.Fab")
			(hide yes)
			(effects
				(font
					(size 1.016 1.016)
					(thickness 0.1524)
				)
			)
		)
		(duplicate_pad_numbers_are_jumpers no)
		(fp_line
			(start 1.2065 2.2479)
			(end 1.2065 -2.2479)
			(stroke
				(width 0.1524)
				(type default)
			)
			(layer "F.SilkS")
		)
		(fp_line
			(start 1.2065 -2.2479)
			(end -1.2065 -2.2479)
			(stroke
				(width 0.1524)
				(type default)
			)
			(layer "F.SilkS")
		)
		(fp_line
			(start -1.2065 2.2479)
			(end 1.2065 2.2479)
			(stroke
				(width 0.1524)
				(type default)
			)
			(layer "F.SilkS")
		)
		(fp_line
			(start -1.2065 -2.2479)
			(end -1.2065 2.2479)
			(stroke
				(width 0.1524)
				(type default)
			)
			(layer "F.SilkS")
		)
		(fp_rect
			(start -0.8255 1.6002)
			(end 0.8255 -1.6002)
			(stroke
				(width 0)
				(type default)
			)
			(fill no)
			(layer "F.CrtYd")
		)
		(fp_poly
			(pts
				(xy -1.4605 2.3241) (xy -1.4605 -2.3241) (xy 1.4605 -2.3241) (xy 1.4605 1.59512) (xy 0.8255 1.59512)
				(xy 0.8255 -1.6002) (xy -0.8255 -1.6002) (xy -0.8255 1.6002) (xy 1.4605 1.6002) (xy 1.4605 2.3241)
			)
			(stroke
				(width 0)
				(type default)
			)
			(fill no)
			(layer "F.CrtYd")
		)
		(fp_rect
			(start -1.4605 2.3241)
			(end 1.4605 -2.3241)
			(stroke
				(width 0)
				(type default)
			)
			(fill no)
			(layer "F.Fab")
		)
		(pad "1" smd rect
			(at 0 -1.417574 180)
			(size 1.905 1.143)
			(layers "F.Cu" "F.Mask" "F.Paste")
			(net "P5V_USB")
		)
		(pad "2" smd rect
			(at 0 1.417574 180)
			(size 1.905 1.143)
			(layers "F.Cu" "F.Mask" "F.Paste")
			(net "P5V_USB_BP1_F")
		)
	)
)
